(kicad_pcb
	(version 20240108)
	(generator "pcbnew")
	(generator_version "8.0")
	(general
		(thickness 1.62)
		(legacy_teardrops no)
	)
	(paper "A4")
	(title_block
		(title "Jetson Orin Baseboard")
		(date "2025-03-12")
		(rev "1.3.4")
		(company "Antmicro Ltd")
		(comment 1 "www.antmicro.com")
		(comment 9 "footprints 351-355 of 677")
	)
	(layers
		(0 "F.Cu" signal)
		(1 "In1.Cu" signal)
		(2 "In2.Cu" signal)
		(3 "In3.Cu" signal)
		(4 "In4.Cu" jumper)
		(5 "In5.Cu" signal)
		(6 "In6.Cu" signal)
		(31 "B.Cu" signal)
		(32 "B.Adhes" user "B.Adhesive")
		(33 "F.Adhes" user "F.Adhesive")
		(34 "B.Paste" user)
		(35 "F.Paste" user)
		(36 "B.SilkS" user "B.Silkscreen")
		(37 "F.SilkS" user "F.Silkscreen")
		(38 "B.Mask" user)
		(39 "F.Mask" user)
		(40 "Dwgs.User" user "User.Drawings")
		(41 "Cmts.User" user "User.Comments")
		(42 "Eco1.User" user "User.Eco1")
		(43 "Eco2.User" user "User.Eco2")
		(44 "Edge.Cuts" user)
		(45 "Margin" user)
		(46 "B.CrtYd" user "B.Courtyard")
		(47 "F.CrtYd" user "F.Courtyard")
		(48 "B.Fab" user)
		(49 "F.Fab" user)
	)
	(footprint "antmicro-footprints:R_0402_1005Metric"
		(layer "B.Cu")
		(at 87.3 106.6 -90)
		(descr "Resistor SMD 0402")
		(tags "resistor SMD 0402")
		(property "Reference" "R217"
			(at -4.1 3.4 90)
			(layer "B.SilkS")
			(effects
				(font
					(size 0.7 0.7)
					(thickness 0.15)
				)
				(justify left bottom mirror)
			)
		)
		(property "Value" "R_0R_0402"
			(at 0 -1.4 90)
			(layer "B.Fab")
			(effects
				(font
					(size 0.7 0.7)
					(thickness 0.15)
				)
				(justify left bottom mirror)
			)
		)
		(property "Footprint" "antmicro-footprints:R_0402_1005Metric"
			(at 0 0 -90)
			(layer "F.Fab")
			(hide yes)
			(effects
				(font
					(size 1.27 1.27)
					(thickness 0.15)
				)
			)
		)
		(property "Datasheet" "https://industrial.panasonic.com/cdbs/www-data/pdf/RDA0000/AOA0000C301.pdf"
			(at 0 0 -90)
			(layer "F.Fab")
			(hide yes)
			(effects
				(font
					(size 1.27 1.27)
					(thickness 0.15)
				)
			)
		)
		(property "Author" "Antmicro"
			(at -19.3 193.9 0)
			(layer "B.Fab")
			(hide yes)
			(effects
				(font
					(size 1 1)
					(thickness 0.15)
				)
				(justify mirror)
			)
		)
		(property "Current" "1A"
			(at -19.3 193.9 0)
			(layer "B.Fab")
			(hide yes)
			(effects
				(font
					(size 1 1)
					(thickness 0.15)
				)
				(justify mirror)
			)
		)
		(property "License" "Apache-2.0"
			(at -19.3 193.9 0)
			(layer "B.Fab")
			(hide yes)
			(effects
				(font
					(size 1 1)
					(thickness 0.15)
				)
				(justify mirror)
			)
		)
		(property "MPN" "ERJ2GE0R00X"
			(at -19.3 193.9 0)
			(layer "B.Fab")
			(hide yes)
			(effects
				(font
					(size 1 1)
					(thickness 0.15)
				)
				(justify mirror)
			)
		)
		(property "Manufacturer" "Panasonic"
			(at -19.3 193.9 0)
			(layer "B.Fab")
			(hide yes)
			(effects
				(font
					(size 1 1)
					(thickness 0.15)
				)
				(justify mirror)
			)
		)
		(property "Tolerance" ""
			(at -19.3 193.9 0)
			(layer "B.Fab")
			(hide yes)
			(effects
				(font
					(size 1 1)
					(thickness 0.15)
				)
				(justify mirror)
			)
		)
		(property "Val" "0R"
			(at -19.3 193.9 0)
			(layer "B.Fab")
			(hide yes)
			(effects
				(font
					(size 1 1)
					(thickness 0.15)
				)
				(justify mirror)
			)
		)
		(sheetname "Peripherals")
		(sheetfile "peripherals.kicad_sch")
		(attr smd)
		(fp_rect
			(start -0.925 0.47)
			(end 0.925 -0.47)
			(stroke
				(width 0.05)
				(type default)
			)
			(fill none)
			(layer "B.CrtYd")
		)
		(fp_rect
			(start -0.5 0.25)
			(end 0.5 -0.25)
			(stroke
				(width 0.15)
				(type solid)
			)
			(fill none)
			(layer "B.Fab")
		)
		(fp_text user "${REFERENCE}"
			(at -0.95 -3.168 90)
			(layer "B.Fab")
			(hide yes)
			(effects
				(font
					(size 0.7 0.7)
					(thickness 0.15)
				)
				(justify left bottom mirror)
			)
		)
		(fp_text user "Author: Antmicro"
			(at -0.95 -4.169 90)
			(layer "B.Fab")
			(hide yes)
			(effects
				(font
					(size 0.7 0.7)
					(thickness 0.15)
				)
				(justify left bottom mirror)
			)
		)
		(fp_text user "License: Apache-2.0"
			(at -0.95 -5.169 90)
			(layer "B.Fab")
			(hide yes)
			(effects
				(font
					(size 0.7 0.7)
					(thickness 0.15)
				)
				(justify left bottom mirror)
			)
		)
		(pad "1" smd roundrect
			(at -0.48 0 270)
			(size 0.59 0.64)
			(layers "B.Cu" "B.Paste" "B.Mask")
			(roundrect_rratio 0.25)
			(net 87 "+3V3")
			(pintype "passive")
		)
		(pad "2" smd roundrect
			(at 0.48 0 270)
			(size 0.59 0.64)
			(layers "B.Cu" "B.Paste" "B.Mask")
			(roundrect_rratio 0.25)
			(net 351 "/Peripherals/GPIOEX_RESET")
			(pintype "passive")
		)
	)
	(footprint "antmicro-footprints:R_0402_1005Metric"
		(layer "B.Cu")
		(at 112.4 105.1 180)
		(descr "Resistor SMD 0402")
		(tags "resistor SMD 0402")
		(property "Reference" "R245"
			(at -3.78 -0.28 0)
			(layer "B.SilkS")
			(effects
				(font
					(size 0.7 0.7)
					(thickness 0.15)
				)
				(justify left bottom mirror)
			)
		)
		(property "Value" "R_0R_0402"
			(at 0 -1.4 0)
			(layer "B.Fab")
			(effects
				(font
					(size 0.7 0.7)
					(thickness 0.15)
				)
				(justify left bottom mirror)
			)
		)
		(property "Footprint" "antmicro-footprints:R_0402_1005Metric"
			(at 0 0 180)
			(layer "F.Fab")
			(hide yes)
			(effects
				(font
					(size 1.27 1.27)
					(thickness 0.15)
				)
			)
		)
		(property "Datasheet" "https://industrial.panasonic.com/cdbs/www-data/pdf/RDA0000/AOA0000C301.pdf"
			(at 0 0 180)
			(layer "F.Fab")
			(hide yes)
			(effects
				(font
					(size 1.27 1.27)
					(thickness 0.15)
				)
			)
		)
		(property "Author" "Antmicro"
			(at 224.8 210.2 0)
			(layer "B.Fab")
			(hide yes)
			(effects
				(font
					(size 1 1)
					(thickness 0.15)
				)
				(justify mirror)
			)
		)
		(property "Current" "1A"
			(at 224.8 210.2 0)
			(layer "B.Fab")
			(hide yes)
			(effects
				(font
					(size 1 1)
					(thickness 0.15)
				)
				(justify mirror)
			)
		)
		(property "License" "Apache-2.0"
			(at 224.8 210.2 0)
			(layer "B.Fab")
			(hide yes)
			(effects
				(font
					(size 1 1)
					(thickness 0.15)
				)
				(justify mirror)
			)
		)
		(property "MPN" "ERJ2GE0R00X"
			(at 224.8 210.2 0)
			(layer "B.Fab")
			(hide yes)
			(effects
				(font
					(size 1 1)
					(thickness 0.15)
				)
				(justify mirror)
			)
		)
		(property "Manufacturer" "Panasonic"
			(at 224.8 210.2 0)
			(layer "B.Fab")
			(hide yes)
			(effects
				(font
					(size 1 1)
					(thickness 0.15)
				)
				(justify mirror)
			)
		)
		(property "Tolerance" ""
			(at 224.8 210.2 0)
			(layer "B.Fab")
			(hide yes)
			(effects
				(font
					(size 1 1)
					(thickness 0.15)
				)
				(justify mirror)
			)
		)
		(property "Val" "0R"
			(at 224.8 210.2 0)
			(layer "B.Fab")
			(hide yes)
			(effects
				(font
					(size 1 1)
					(thickness 0.15)
				)
				(justify mirror)
			)
		)
		(sheetname "USB3")
		(sheetfile "usb3.kicad_sch")
		(attr smd exclude_from_pos_files exclude_from_bom dnp)
		(fp_rect
			(start -0.925 0.47)
			(end 0.925 -0.47)
			(stroke
				(width 0.05)
				(type default)
			)
			(fill none)
			(layer "B.CrtYd")
		)
		(fp_rect
			(start -0.5 0.25)
			(end 0.5 -0.25)
			(stroke
				(width 0.15)
				(type solid)
			)
			(fill none)
			(layer "B.Fab")
		)
		(fp_text user "${REFERENCE}"
			(at -0.95 -3.168 0)
			(layer "B.Fab")
			(hide yes)
			(effects
				(font
					(size 0.7 0.7)
					(thickness 0.15)
				)
				(justify left bottom mirror)
			)
		)
		(fp_text user "License: Apache-2.0"
			(at -0.95 -5.169 0)
			(layer "B.Fab")
			(hide yes)
			(effects
				(font
					(size 0.7 0.7)
					(thickness 0.15)
				)
				(justify left bottom mirror)
			)
		)
		(fp_text user "Author: Antmicro"
			(at -0.95 -4.169 0)
			(layer "B.Fab")
			(hide yes)
			(effects
				(font
					(size 0.7 0.7)
					(thickness 0.15)
				)
				(justify left bottom mirror)
			)
		)
		(pad "1" smd roundrect
			(at -0.48 0 180)
			(size 0.59 0.64)
			(layers "B.Cu" "B.Paste" "B.Mask")
			(roundrect_rratio 0.25)
			(net 714 "GPIO010")
			(pintype "passive")
		)
		(pad "2" smd roundrect
			(at 0.48 0 180)
			(size 0.59 0.64)
			(layers "B.Cu" "B.Paste" "B.Mask")
			(roundrect_rratio 0.25)
			(net 317 "/USB3/~{USBC1_INT}")
			(pintype "passive")
		)
	)
	(footprint "antmicro-footprints:FB_0805_2012Metric"
		(layer "B.Cu")
		(at 47.8 93.6375 90)
		(descr "FERRITE BEAD 0805")
		(tags "FERRITE BEAD 0805")
		(property "Reference" "FB3"
			(at 0.5575 -0.97 -90)
			(layer "B.SilkS")
			(effects
				(font
					(size 0.7 0.7)
					(thickness 0.15)
				)
				(justify left bottom mirror)
			)
		)
		(property "Value" "FB_220Z_2A_Murata-BLM21PG_0805"
			(at 0 -1.8 -90)
			(layer "B.Fab")
			(effects
				(font
					(size 0.7 0.7)
					(thickness 0.15)
				)
				(justify left bottom mirror)
			)
		)
		(property "Footprint" "antmicro-footprints:FB_0805_2012Metric"
			(at 0 0 90)
			(layer "F.Fab")
			(hide yes)
			(effects
				(font
					(size 1.27 1.27)
					(thickness 0.15)
				)
			)
		)
		(property "Datasheet" "https://www.murata.com/products/productdata/8796738977822/ENFA0005.pdf?1653276712000"
			(at 0 0 90)
			(layer "F.Fab")
			(hide yes)
			(effects
				(font
					(size 1.27 1.27)
					(thickness 0.15)
				)
			)
		)
		(property "Author" "Antmicro"
			(at 141.4375 45.8375 0)
			(layer "B.Fab")
			(hide yes)
			(effects
				(font
					(size 1 1)
					(thickness 0.15)
				)
				(justify mirror)
			)
		)
		(property "Current" ""
			(at 141.4375 45.8375 0)
			(layer "B.Fab")
			(hide yes)
			(effects
				(font
					(size 1 1)
					(thickness 0.15)
				)
				(justify mirror)
			)
		)
		(property "License" "Apache-2.0"
			(at 141.4375 45.8375 0)
			(layer "B.Fab")
			(hide yes)
			(effects
				(font
					(size 1 1)
					(thickness 0.15)
				)
				(justify mirror)
			)
		)
		(property "MPN" "BLM21PG221SN1D"
			(at 141.4375 45.8375 0)
			(layer "B.Fab")
			(hide yes)
			(effects
				(font
					(size 1 1)
					(thickness 0.15)
				)
				(justify mirror)
			)
		)
		(property "Manufacturer" "Murata"
			(at 141.4375 45.8375 0)
			(layer "B.Fab")
			(hide yes)
			(effects
				(font
					(size 1 1)
					(thickness 0.15)
				)
				(justify mirror)
			)
		)
		(property "Val" "220Z/2A"
			(at 141.4375 45.8375 0)
			(layer "B.Fab")
			(hide yes)
			(effects
				(font
					(size 1 1)
					(thickness 0.15)
				)
				(justify mirror)
			)
		)
		(sheetname "Ethernet")
		(sheetfile "ethernet.kicad_sch")
		(attr smd)
		(fp_line
			(start 0.281 -0.698)
			(end -0.319 -0.698)
			(stroke
				(width 0.15)
				(type solid)
			)
			(layer "B.SilkS")
		)
		(fp_line
			(start 0.299 0.698)
			(end -0.299 0.698)
			(stroke
				(width 0.15)
				(type solid)
			)
			(layer "B.SilkS")
		)
		(fp_rect
			(start 1.95 0.9)
			(end -1.95 -0.9)
			(stroke
				(width 0.05)
				(type default)
			)
			(fill none)
			(layer "B.CrtYd")
		)
		(fp_line
			(start 0.948 -0.681)
			(end -0.948 -0.681)
			(stroke
				(width 0.15)
				(type solid)
			)
			(layer "B.Fab")
		)
		(fp_line
			(start 0.948 -0.676)
			(end 0.948 0.676)
			(stroke
				(width 0.15)
				(type solid)
			)
			(layer "B.Fab")
		)
		(fp_line
			(start -0.948 -0.676)
			(end -0.948 0.676)
			(stroke
				(width 0.15)
				(type solid)
			)
			(layer "B.Fab")
		)
		(fp_line
			(start 0.948 0.681)
			(end -0.948 0.681)
			(stroke
				(width 0.15)
				(type solid)
			)
			(layer "B.Fab")
		)
		(fp_text user "Author: Antmicro"
			(at -1.9 -4.4 -90)
			(layer "B.Fab")
			(hide yes)
			(effects
				(font
					(size 0.7 0.7)
					(thickness 0.15)
				)
				(justify left bottom mirror)
			)
		)
		(fp_text user "${REFERENCE}"
			(at -1.9 -3.1 -90)
			(layer "B.Fab")
			(hide yes)
			(effects
				(font
					(size 0.7 0.7)
					(thickness 0.15)
				)
				(justify left bottom mirror)
			)
		)
		(fp_text user "License: Apache-2.0"
			(at -1.9 -5.75 -90)
			(layer "B.Fab")
			(hide yes)
			(effects
				(font
					(size 0.7 0.7)
					(thickness 0.15)
				)
				(justify left bottom mirror)
			)
		)
		(pad "1" smd roundrect
			(at -1.1 0 90)
			(size 1.2 1.3)
			(layers "B.Cu" "B.Paste" "B.Mask")
			(roundrect_rratio 0.25)
			(net 148 "Net-(D12-Pad1)")
			(pintype "passive")
		)
		(pad "2" smd roundrect
			(at 1.1 0 90)
			(size 1.2 1.3)
			(layers "B.Cu" "B.Paste" "B.Mask")
			(roundrect_rratio 0.25)
			(net 499 "/Ethernet/VSS")
			(pintype "passive")
		)
	)
	(footprint "antmicro-footprints:C_0402_1005Metric"
		(layer "B.Cu")
		(at 49.03 82.19)
		(descr "Capacitor SMD 0402")
		(tags "capacitor SMD 0402")
		(property "Reference" "C50"
			(at -1.105 0.51 0)
			(layer "B.SilkS")
			(effects
				(font
					(size 0.7 0.7)
					(thickness 0.15)
				)
				(justify right top mirror)
			)
		)
		(property "Value" "C_100n_0402"
			(at 0 -1.4 0)
			(layer "B.Fab")
			(effects
				(font
					(size 0.7 0.7)
					(thickness 0.15)
				)
				(justify right top mirror)
			)
		)
		(property "Footprint" "antmicro-footprints:C_0402_1005Metric"
			(at 0 0 0)
			(layer "F.Fab")
			(hide yes)
			(effects
				(font
					(size 1.27 1.27)
					(thickness 0.15)
				)
			)
		)
		(property "Datasheet" "https://www.murata.com/products/productdetail?partno=GRM155R61H104KE14%23"
			(at 0 0 0)
			(layer "F.Fab")
			(hide yes)
			(effects
				(font
					(size 1.27 1.27)
					(thickness 0.15)
				)
			)
		)
		(property "Author" "Antmicro"
			(at 134.58 27.68 90)
			(layer "B.Fab")
			(hide yes)
			(effects
				(font
					(size 1 1)
					(thickness 0.15)
				)
				(justify mirror)
			)
		)
		(property "Dielectric" "X5R"
			(at 134.58 27.68 90)
			(layer "B.Fab")
			(hide yes)
			(effects
				(font
					(size 1 1)
					(thickness 0.15)
				)
				(justify mirror)
			)
		)
		(property "License" "Apache-2.0"
			(at 134.58 27.68 90)
			(layer "B.Fab")
			(hide yes)
			(effects
				(font
					(size 1 1)
					(thickness 0.15)
				)
				(justify mirror)
			)
		)
		(property "MPN" "GRM155R61H104KE14D"
			(at 134.58 27.68 90)
			(layer "B.Fab")
			(hide yes)
			(effects
				(font
					(size 1 1)
					(thickness 0.15)
				)
				(justify mirror)
			)
		)
		(property "Manufacturer" "Murata"
			(at 134.58 27.68 90)
			(layer "B.Fab")
			(hide yes)
			(effects
				(font
					(size 1 1)
					(thickness 0.15)
				)
				(justify mirror)
			)
		)
		(property "Val" "100n"
			(at 134.58 27.68 90)
			(layer "B.Fab")
			(hide yes)
			(effects
				(font
					(size 1 1)
					(thickness 0.15)
				)
				(justify mirror)
			)
		)
		(property "Voltage" "50V"
			(at 134.58 27.68 90)
			(layer "B.Fab")
			(hide yes)
			(effects
				(font
					(size 1 1)
					(thickness 0.15)
				)
				(justify mirror)
			)
		)
		(sheetname "Supply")
		(sheetfile "supply.kicad_sch")
		(attr smd)
		(fp_rect
			(start -0.925 0.47)
			(end 0.925 -0.47)
			(stroke
				(width 0.05)
				(type default)
			)
			(fill none)
			(layer "B.CrtYd")
		)
		(fp_line
			(start -0.494 -0.248)
			(end 0.504 -0.248)
			(stroke
				(width 0.15)
				(type solid)
			)
			(layer "B.Fab")
		)
		(fp_line
			(start -0.494 0.25)
			(end -0.494 -0.248)
			(stroke
				(width 0.15)
				(type solid)
			)
			(layer "B.Fab")
		)
		(fp_line
			(start 0.504 -0.248)
			(end 0.504 0.25)
			(stroke
				(width 0.15)
				(type solid)
			)
			(layer "B.Fab")
		)
		(fp_line
			(start 0.504 0.25)
			(end -0.494 0.25)
			(stroke
				(width 0.15)
				(type solid)
			)
			(layer "B.Fab")
		)
		(fp_text user "License: Apache-2.0"
			(at -0.932 -5.17 0)
			(layer "B.Fab")
			(hide yes)
			(effects
				(font
					(size 0.7 0.7)
					(thickness 0.15)
				)
				(justify right top mirror)
			)
		)
		(fp_text user "Author: Antmicro"
			(at -0.932 -4.17 0)
			(layer "B.Fab")
			(hide yes)
			(effects
				(font
					(size 0.7 0.7)
					(thickness 0.15)
				)
				(justify right top mirror)
			)
		)
		(fp_text user "${REFERENCE}"
			(at -0.932 -3.168 0)
			(layer "B.Fab")
			(hide yes)
			(effects
				(font
					(size 0.7 0.7)
					(thickness 0.15)
				)
				(justify right top mirror)
			)
		)
		(pad "1" smd roundrect
			(at -0.48 0)
			(size 0.59 0.64)
			(layers "B.Cu" "B.Paste" "B.Mask")
			(roundrect_rratio 0.25)
			(net 135 "Net-(Q18-G)")
			(pintype "passive")
		)
		(pad "2" smd roundrect
			(at 0.48 0)
			(size 0.59 0.64)
			(layers "B.Cu" "B.Paste" "B.Mask")
			(roundrect_rratio 0.25)
			(net 115 "VCC")
			(pintype "passive")
		)
	)
	(footprint "antmicro-footprints:TP_SMD_0.75mm"
		(layer "B.Cu")
		(at 68.165 126.07)
		(property "Reference" "TP55"
			(at -0.56 0.8308 0)
			(layer "B.SilkS")
			(hide yes)
			(effects
				(font
					(size 0.7 0.7)
					(thickness 0.15)
				)
				(justify right bottom mirror)
			)
		)
		(property "Value" "TP_0.75mm_SMD"
			(at 0 -1.2 0)
			(layer "B.Fab")
			(effects
				(font
					(size 0.7 0.7)
					(thickness 0.15)
				)
				(justify right bottom mirror)
			)
		)
		(property "Footprint" "antmicro-footprints:TP_SMD_0.75mm"
			(at 0 0 0)
			(layer "F.Fab")
			(hide yes)
			(effects
				(font
					(size 1.27 1.27)
					(thickness 0.15)
				)
			)
		)
		(property "Author" "Antmicro"
			(at 0 0 0)
			(layer "B.Fab")
			(hide yes)
			(effects
				(font
					(size 1 1)
					(thickness 0.15)
				)
				(justify mirror)
			)
		)
		(property "License" "Apache-2.0"
			(at 0 0 0)
			(layer "B.Fab")
			(hide yes)
			(effects
				(font
					(size 1 1)
					(thickness 0.15)
				)
				(justify mirror)
			)
		)
		(property "MPN" ""
			(at 0 0 0)
			(layer "B.Fab")
			(hide yes)
			(effects
				(font
					(size 1 1)
					(thickness 0.15)
				)
				(justify mirror)
			)
		)
		(property "Manufacturer" ""
			(at 0 0 0)
			(layer "B.Fab")
			(hide yes)
			(effects
				(font
					(size 1 1)
					(thickness 0.15)
				)
				(justify mirror)
			)
		)
		(sheetname "Supply")
		(sheetfile "supply.kicad_sch")
		(attr exclude_from_pos_files exclude_from_bom)
		(fp_circle
			(center 0 0)
			(end 0.475 0)
			(stroke
				(width 0.05)
				(type default)
			)
			(fill none)
			(layer "B.CrtYd")
		)
		(fp_text user "Author: Antmicro"
			(at -0.4 -3.901 0)
			(layer "B.Fab")
			(hide yes)
			(effects
				(font
					(size 0.7 0.7)
					(thickness 0.15)
				)
				(justify right bottom mirror)
			)
		)
		(fp_text user "${REFERENCE}"
			(at -0.4 -2.7 0)
			(layer "B.Fab")
			(hide yes)
			(effects
				(font
					(size 0.7 0.7)
					(thickness 0.15)
				)
				(justify right bottom mirror)
			)
		)
		(fp_text user "License: Apache-2.0"
			(at -0.4 -5.101 0)
			(layer "B.Fab")
			(hide yes)
			(effects
				(font
					(size 0.7 0.7)
					(thickness 0.15)
				)
				(justify right bottom mirror)
			)
		)
		(pad "1" smd circle
			(at 0 0)
			(size 0.75 0.75)
			(layers "B.Cu" "B.Mask")
			(net 112 "+1V8")
			(pinfunction "1")
			(pintype "passive")
		)
	)
)
